(kicad_pcb
	(version 20260206)
	(generator "pcbnew")
	(generator_version "10.0")
	(general
		(thickness 1.6)
		(legacy_teardrops no)
	)
	(paper "A4")
	(title_block
		(title "panther-plus-userver — 13130-1b_20150205.brd")
		(comment 1 "Honey Badger (Wiwynn) / footprint 1214 of 1509 (DIMM3), pads 23-29 of 210")
	)
	(layers
		(0 "F.Cu" signal "TOP")
		(4 "In1.Cu" signal "L2")
		(6 "In2.Cu" signal "L3")
		(8 "In3.Cu" signal "L4")
		(10 "In4.Cu" signal "L5")
		(12 "In5.Cu" signal "L6")
		(14 "In6.Cu" signal "L7")
		(16 "In7.Cu" signal "L8")
		(18 "In8.Cu" signal "L9")
		(20 "In9.Cu" signal "L10")
		(22 "In10.Cu" signal "L11")
		(2 "B.Cu" signal "BOTTOM")
		(9 "F.Adhes" user "F.Adhesive")
		(11 "B.Adhes" user "B.Adhesive")
		(13 "F.Paste" user "Package Geometry/Pastemask Top")
		(15 "B.Paste" user "Package Geometry/Pastemask Bottom")
		(5 "F.SilkS" user "Ref Des/Silkscreen Top")
		(7 "B.SilkS" user "Ref Des/Silkscreen Bottom")
		(1 "F.Mask" user "Board Geometry/Soldermask Top")
		(3 "B.Mask" user "Board Geometry/Soldermask Bottom")
		(17 "Dwgs.User" user "User.Drawings")
		(19 "Cmts.User" user "User.Comments")
		(21 "Eco1.User" user "User.Eco1")
		(23 "Eco2.User" user "User.Eco2")
		(25 "Edge.Cuts" user "Board Geometry/Outline")
		(27 "Margin" user)
		(31 "F.CrtYd" user "Package Geometry/Place Bound Top")
		(29 "B.CrtYd" user "Package Geometry/Place Bound Bottom")
		(35 "F.Fab" user "Ref Des/Assembly Top")
		(33 "B.Fab" user "Ref Des/Assembly Bottom")
	)
	(footprint ""
		(layer "B.Cu")
		(at 159.999934 -5.790692)
		(property "Reference" "DIMM3"
			(at 0 0 0)
			(layer "B.SilkS")
			(hide yes)
			(effects
				(font
					(size 1.27 1.27)
				)
				(justify mirror)
			)
		)
		(property "Value" "DDR3-204P-142-COLAY-1-GP-U"
			(at 41.312338 -16.676878 0)
			(unlocked yes)
			(layer "B.Fab")
			(hide yes)
			(effects
				(font
					(size 1.016 1.016)
					(thickness 0.1524)
				)
				(justify mirror)
			)
		)
		(property "Device Type" "AS0A626-J8R6-7H-COLAY-1"
			(at 41.312338 -18.200878 0)
			(unlocked yes)
			(layer "B.Fab")
			(hide yes)
			(effects
				(font
					(size 1.016 1.016)
					(thickness 0.1524)
				)
				(justify mirror)
			)
		)
		(duplicate_pad_numbers_are_jumpers no)
		(pad "21" smd custom
			(at -25.649936 -4.100068 180)
			(size 0.1143 0.1143)
			(layers "B.Cu" "B.Mask" "B.Paste")
			(net "M_B_DQ9")
			(options
				(clearance outline)
				(anchor circle)
			)
			(primitives
				(gr_poly
					(pts
						(xy 0 -0.9017) (xy -0.03175 -0.89916) (xy -0.0635 -0.889) (xy -0.09144 -0.87376) (xy -0.11684 -0.85344)
						(xy -0.13716 -0.82804) (xy -0.1524 -0.8001) (xy -0.16256 -0.76835) (xy -0.1651 -0.7366) (xy -0.1651 -0.44958)
						(xy -0.17272 -0.44196) (xy -0.19812 -0.4064) (xy -0.2032 -0.39624) (xy -0.20701 -0.38735) (xy -0.21209 -0.37719)
						(xy -0.2159 -0.36703) (xy -0.21844 -0.35687) (xy -0.22225 -0.34544) (xy -0.22352 -0.33528) (xy -0.22606 -0.32512)
						(xy -0.22733 -0.31369) (xy -0.22733 -0.30353) (xy -0.2286 -0.2921) (xy -0.22733 -0.28067) (xy -0.22733 -0.27051)
						(xy -0.22606 -0.25908) (xy -0.22352 -0.24892) (xy -0.22225 -0.23876) (xy -0.21844 -0.22733) (xy -0.2159 -0.21717)
						(xy -0.21209 -0.20701) (xy -0.20701 -0.19685) (xy -0.2032 -0.18796) (xy -0.19812 -0.1778) (xy -0.17272 -0.14224)
						(xy -0.1651 -0.13462) (xy -0.1651 0.7366) (xy -0.16256 0.76835) (xy -0.1524 0.8001) (xy -0.13716 0.82804)
						(xy -0.11684 0.85344) (xy -0.09144 0.87376) (xy -0.0635 0.889) (xy -0.03175 0.89916) (xy 0 0.9017)
						(xy 0.03175 0.89916) (xy 0.0635 0.889) (xy 0.09144 0.87376) (xy 0.11684 0.85344) (xy 0.13716 0.82804)
						(xy 0.1524 0.8001) (xy 0.16256 0.76835) (xy 0.1651 0.7366) (xy 0.1651 -0.13462) (xy 0.17272 -0.14224)
						(xy 0.19812 -0.1778) (xy 0.2032 -0.18796) (xy 0.20701 -0.19685) (xy 0.21209 -0.20701) (xy 0.2159 -0.21717)
						(xy 0.21844 -0.22733) (xy 0.22225 -0.23876) (xy 0.22352 -0.24892) (xy 0.22606 -0.25908) (xy 0.22733 -0.27051)
						(xy 0.22733 -0.28067) (xy 0.2286 -0.2921) (xy 0.22733 -0.30353) (xy 0.22733 -0.31369) (xy 0.22606 -0.32512)
						(xy 0.22352 -0.33528) (xy 0.22225 -0.34544) (xy 0.21844 -0.35687) (xy 0.2159 -0.36703) (xy 0.21209 -0.37719)
						(xy 0.20701 -0.38735) (xy 0.2032 -0.39624) (xy 0.19812 -0.4064) (xy 0.17272 -0.44196) (xy 0.1651 -0.44958)
						(xy 0.1651 -0.7366) (xy 0.16256 -0.76835) (xy 0.1524 -0.8001) (xy 0.13716 -0.82804) (xy 0.11684 -0.85344)
						(xy 0.09144 -0.87376) (xy 0.0635 -0.889) (xy 0.03175 -0.89916)
					)
					(width 0)
					(fill yes)
				)
			)
		)
		(pad "22" smd custom
			(at -25.349962 4.100068 180)
			(size 0.1143 0.1143)
			(layers "B.Cu" "B.Mask" "B.Paste")
			(net "M_B_DQ12")
			(options
				(clearance outline)
				(anchor circle)
			)
			(primitives
				(gr_poly
					(pts
						(xy 0 -0.9017) (xy -0.03175 -0.89916) (xy -0.0635 -0.889) (xy -0.09144 -0.87376) (xy -0.11684 -0.85344)
						(xy -0.13716 -0.82804) (xy -0.1524 -0.8001) (xy -0.16256 -0.76835) (xy -0.1651 -0.7366) (xy -0.1651 0.13462)
						(xy -0.17272 0.14224) (xy -0.19812 0.1778) (xy -0.2032 0.18796) (xy -0.20701 0.19685) (xy -0.21209 0.20701)
						(xy -0.2159 0.21717) (xy -0.21844 0.22733) (xy -0.22225 0.23876) (xy -0.22352 0.24892) (xy -0.22606 0.25908)
						(xy -0.22733 0.27051) (xy -0.22733 0.28067) (xy -0.2286 0.2921) (xy -0.22733 0.30353) (xy -0.22733 0.31369)
						(xy -0.22606 0.32512) (xy -0.22352 0.33528) (xy -0.22225 0.34544) (xy -0.21844 0.35687) (xy -0.2159 0.36703)
						(xy -0.21209 0.37719) (xy -0.20701 0.38735) (xy -0.2032 0.39624) (xy -0.19812 0.4064) (xy -0.17272 0.44196)
						(xy -0.1651 0.44958) (xy -0.1651 0.7366) (xy -0.16256 0.76835) (xy -0.1524 0.8001) (xy -0.13716 0.82804)
						(xy -0.11684 0.85344) (xy -0.09144 0.87376) (xy -0.0635 0.889) (xy -0.03175 0.89916) (xy 0 0.9017)
						(xy 0.03175 0.89916) (xy 0.0635 0.889) (xy 0.09144 0.87376) (xy 0.11684 0.85344) (xy 0.13716 0.82804)
						(xy 0.1524 0.8001) (xy 0.16256 0.76835) (xy 0.1651 0.7366) (xy 0.1651 0.44958) (xy 0.17272 0.44196)
						(xy 0.19812 0.4064) (xy 0.2032 0.39624) (xy 0.20701 0.38735) (xy 0.21209 0.37719) (xy 0.2159 0.36703)
						(xy 0.21844 0.35687) (xy 0.22225 0.34544) (xy 0.22352 0.33528) (xy 0.22606 0.32512) (xy 0.22733 0.31369)
						(xy 0.22733 0.30353) (xy 0.2286 0.2921) (xy 0.22733 0.28067) (xy 0.22733 0.27051) (xy 0.22606 0.25908)
						(xy 0.22352 0.24892) (xy 0.22225 0.23876) (xy 0.21844 0.22733) (xy 0.2159 0.21717) (xy 0.21209 0.20701)
						(xy 0.20701 0.19685) (xy 0.2032 0.18796) (xy 0.19812 0.1778) (xy 0.17272 0.14224) (xy 0.1651 0.13462)
						(xy 0.1651 -0.7366) (xy 0.16256 -0.76835) (xy 0.1524 -0.8001) (xy 0.13716 -0.82804) (xy 0.11684 -0.85344)
						(xy 0.09144 -0.87376) (xy 0.0635 -0.889) (xy 0.03175 -0.89916)
					)
					(width 0)
					(fill yes)
				)
			)
		)
		(pad "23" smd custom
			(at -25.049988 -4.100068 180)
			(size 0.1143 0.1143)
			(layers "B.Cu" "B.Mask" "B.Paste")
			(net "GND")
			(options
				(clearance outline)
				(anchor circle)
			)
			(primitives
				(gr_poly
					(pts
						(xy 0 -0.9017) (xy -0.03175 -0.89916) (xy -0.0635 -0.889) (xy -0.09144 -0.87376) (xy -0.11684 -0.85344)
						(xy -0.13716 -0.82804) (xy -0.1524 -0.8001) (xy -0.16256 -0.76835) (xy -0.1651 -0.7366) (xy -0.1651 -0.19685)
						(xy -0.17272 -0.18923) (xy -0.17907 -0.18034) (xy -0.18669 -0.17145) (xy -0.19177 -0.16256) (xy -0.19812 -0.15367)
						(xy -0.20828 -0.13335) (xy -0.21971 -0.10287) (xy -0.22225 -0.09271) (xy -0.22479 -0.08128) (xy -0.22606 -0.07112)
						(xy -0.2286 -0.05969) (xy -0.2286 -0.01651) (xy -0.22606 -0.00508) (xy -0.22479 0.00508) (xy -0.22225 0.01651)
						(xy -0.21971 0.02667) (xy -0.20828 0.05715) (xy -0.19812 0.07747) (xy -0.19177 0.08636) (xy -0.18669 0.09525)
						(xy -0.17907 0.10414) (xy -0.17272 0.11303) (xy -0.1651 0.12065) (xy -0.1651 0.7366) (xy -0.16256 0.76835)
						(xy -0.1524 0.8001) (xy -0.13716 0.82804) (xy -0.11684 0.85344) (xy -0.09144 0.87376) (xy -0.0635 0.889)
						(xy -0.03175 0.89916) (xy 0 0.9017) (xy 0.03175 0.89916) (xy 0.0635 0.889) (xy 0.09144 0.87376)
						(xy 0.11684 0.85344) (xy 0.13716 0.82804) (xy 0.1524 0.8001) (xy 0.16256 0.76835) (xy 0.1651 0.7366)
						(xy 0.1651 0.11938) (xy 0.17272 0.11176) (xy 0.19812 0.0762) (xy 0.2032 0.06604) (xy 0.20701 0.05715)
						(xy 0.21209 0.04699) (xy 0.2159 0.03683) (xy 0.21844 0.02667) (xy 0.22225 0.01524) (xy 0.22352 0.00508)
						(xy 0.22606 -0.00508) (xy 0.22733 -0.01651) (xy 0.22733 -0.02667) (xy 0.2286 -0.0381) (xy 0.22733 -0.04953)
						(xy 0.22733 -0.05969) (xy 0.22606 -0.07112) (xy 0.22352 -0.08128) (xy 0.22225 -0.09144) (xy 0.21844 -0.10287)
						(xy 0.2159 -0.11303) (xy 0.21209 -0.12319) (xy 0.20701 -0.13335) (xy 0.2032 -0.14224) (xy 0.19812 -0.1524)
						(xy 0.17272 -0.18796) (xy 0.1651 -0.19558) (xy 0.1651 -0.7366) (xy 0.16256 -0.76835) (xy 0.1524 -0.8001)
						(xy 0.13716 -0.82804) (xy 0.11684 -0.85344) (xy 0.09144 -0.87376) (xy 0.0635 -0.889) (xy 0.03175 -0.89916)
					)
					(width 0)
					(fill yes)
				)
			)
		)
		(pad "24" smd custom
			(at -24.750014 4.100068 180)
			(size 0.1143 0.1143)
			(layers "B.Cu" "B.Mask" "B.Paste")
			(net "M_B_DQ13")
			(options
				(clearance outline)
				(anchor circle)
			)
			(primitives
				(gr_poly
					(pts
						(xy 0 -0.9017) (xy -0.03175 -0.89916) (xy -0.0635 -0.889) (xy -0.09144 -0.87376) (xy -0.11684 -0.85344)
						(xy -0.13716 -0.82804) (xy -0.1524 -0.8001) (xy -0.16256 -0.76835) (xy -0.1651 -0.7366) (xy -0.1651 -0.11938)
						(xy -0.17272 -0.11176) (xy -0.19812 -0.0762) (xy -0.2032 -0.06604) (xy -0.20701 -0.05715) (xy -0.21209 -0.04699)
						(xy -0.2159 -0.03683) (xy -0.21844 -0.02667) (xy -0.22225 -0.01524) (xy -0.22352 -0.00508) (xy -0.22606 0.00508)
						(xy -0.22733 0.01651) (xy -0.22733 0.02667) (xy -0.2286 0.0381) (xy -0.22733 0.04953) (xy -0.22733 0.05969)
						(xy -0.22606 0.07112) (xy -0.22352 0.08128) (xy -0.22225 0.09144) (xy -0.21844 0.10287) (xy -0.2159 0.11303)
						(xy -0.21209 0.12319) (xy -0.20701 0.13335) (xy -0.2032 0.14224) (xy -0.19812 0.1524) (xy -0.17272 0.18796)
						(xy -0.1651 0.19558) (xy -0.1651 0.7366) (xy -0.16256 0.76835) (xy -0.1524 0.8001) (xy -0.13716 0.82804)
						(xy -0.11684 0.85344) (xy -0.09144 0.87376) (xy -0.0635 0.889) (xy -0.03175 0.89916) (xy 0 0.9017)
						(xy 0.03175 0.89916) (xy 0.0635 0.889) (xy 0.09144 0.87376) (xy 0.11684 0.85344) (xy 0.13716 0.82804)
						(xy 0.1524 0.8001) (xy 0.16256 0.76835) (xy 0.1651 0.7366) (xy 0.1651 0.19685) (xy 0.17272 0.18923)
						(xy 0.17907 0.18034) (xy 0.18669 0.17145) (xy 0.19177 0.16256) (xy 0.19812 0.15367) (xy 0.20828 0.13335)
						(xy 0.21971 0.10287) (xy 0.22225 0.09271) (xy 0.22479 0.08128) (xy 0.22606 0.07112) (xy 0.2286 0.05969)
						(xy 0.2286 0.01651) (xy 0.22606 0.00508) (xy 0.22479 -0.00508) (xy 0.22225 -0.01651) (xy 0.21971 -0.02667)
						(xy 0.20828 -0.05715) (xy 0.19812 -0.07747) (xy 0.19177 -0.08636) (xy 0.18669 -0.09525) (xy 0.17907 -0.10414)
						(xy 0.17272 -0.11303) (xy 0.1651 -0.12065) (xy 0.1651 -0.7366) (xy 0.16256 -0.76835) (xy 0.1524 -0.8001)
						(xy 0.13716 -0.82804) (xy 0.11684 -0.85344) (xy 0.09144 -0.87376) (xy 0.0635 -0.889) (xy 0.03175 -0.89916)
					)
					(width 0)
					(fill yes)
				)
			)
		)
		(pad "25" smd custom
			(at -24.45004 -4.100068 180)
			(size 0.1143 0.1143)
			(layers "B.Cu" "B.Mask" "B.Paste")
			(net "M_B_DQS_DN1")
			(options
				(clearance outline)
				(anchor circle)
			)
			(primitives
				(gr_poly
					(pts
						(xy 0 -0.9017) (xy -0.03175 -0.89916) (xy -0.0635 -0.889) (xy -0.09144 -0.87376) (xy -0.11684 -0.85344)
						(xy -0.13716 -0.82804) (xy -0.1524 -0.8001) (xy -0.16256 -0.76835) (xy -0.1651 -0.7366) (xy -0.1651 -0.44958)
						(xy -0.17272 -0.44196) (xy -0.19812 -0.4064) (xy -0.2032 -0.39624) (xy -0.20701 -0.38735) (xy -0.21209 -0.37719)
						(xy -0.2159 -0.36703) (xy -0.21844 -0.35687) (xy -0.22225 -0.34544) (xy -0.22352 -0.33528) (xy -0.22606 -0.32512)
						(xy -0.22733 -0.31369) (xy -0.22733 -0.30353) (xy -0.2286 -0.2921) (xy -0.22733 -0.28067) (xy -0.22733 -0.27051)
						(xy -0.22606 -0.25908) (xy -0.22352 -0.24892) (xy -0.22225 -0.23876) (xy -0.21844 -0.22733) (xy -0.2159 -0.21717)
						(xy -0.21209 -0.20701) (xy -0.20701 -0.19685) (xy -0.2032 -0.18796) (xy -0.19812 -0.1778) (xy -0.17272 -0.14224)
						(xy -0.1651 -0.13462) (xy -0.1651 0.7366) (xy -0.16256 0.76835) (xy -0.1524 0.8001) (xy -0.13716 0.82804)
						(xy -0.11684 0.85344) (xy -0.09144 0.87376) (xy -0.0635 0.889) (xy -0.03175 0.89916) (xy 0 0.9017)
						(xy 0.03175 0.89916) (xy 0.0635 0.889) (xy 0.09144 0.87376) (xy 0.11684 0.85344) (xy 0.13716 0.82804)
						(xy 0.1524 0.8001) (xy 0.16256 0.76835) (xy 0.1651 0.7366) (xy 0.1651 -0.13462) (xy 0.17272 -0.14224)
						(xy 0.19812 -0.1778) (xy 0.2032 -0.18796) (xy 0.20701 -0.19685) (xy 0.21209 -0.20701) (xy 0.2159 -0.21717)
						(xy 0.21844 -0.22733) (xy 0.22225 -0.23876) (xy 0.22352 -0.24892) (xy 0.22606 -0.25908) (xy 0.22733 -0.27051)
						(xy 0.22733 -0.28067) (xy 0.2286 -0.2921) (xy 0.22733 -0.30353) (xy 0.22733 -0.31369) (xy 0.22606 -0.32512)
						(xy 0.22352 -0.33528) (xy 0.22225 -0.34544) (xy 0.21844 -0.35687) (xy 0.2159 -0.36703) (xy 0.21209 -0.37719)
						(xy 0.20701 -0.38735) (xy 0.2032 -0.39624) (xy 0.19812 -0.4064) (xy 0.17272 -0.44196) (xy 0.1651 -0.44958)
						(xy 0.1651 -0.7366) (xy 0.16256 -0.76835) (xy 0.1524 -0.8001) (xy 0.13716 -0.82804) (xy 0.11684 -0.85344)
						(xy 0.09144 -0.87376) (xy 0.0635 -0.889) (xy 0.03175 -0.89916)
					)
					(width 0)
					(fill yes)
				)
			)
		)
		(pad "26" smd custom
			(at -24.150066 4.100068 180)
			(size 0.1143 0.1143)
			(layers "B.Cu" "B.Mask" "B.Paste")
			(net "GND")
			(options
				(clearance outline)
				(anchor circle)
			)
			(primitives
				(gr_poly
					(pts
						(xy 0 -0.9017) (xy -0.03175 -0.89916) (xy -0.0635 -0.889) (xy -0.09144 -0.87376) (xy -0.11684 -0.85344)
						(xy -0.13716 -0.82804) (xy -0.1524 -0.8001) (xy -0.16256 -0.76835) (xy -0.1651 -0.7366) (xy -0.1651 0.13462)
						(xy -0.17272 0.14224) (xy -0.19812 0.1778) (xy -0.2032 0.18796) (xy -0.20701 0.19685) (xy -0.21209 0.20701)
						(xy -0.2159 0.21717) (xy -0.21844 0.22733) (xy -0.22225 0.23876) (xy -0.22352 0.24892) (xy -0.22606 0.25908)
						(xy -0.22733 0.27051) (xy -0.22733 0.28067) (xy -0.2286 0.2921) (xy -0.22733 0.30353) (xy -0.22733 0.31369)
						(xy -0.22606 0.32512) (xy -0.22352 0.33528) (xy -0.22225 0.34544) (xy -0.21844 0.35687) (xy -0.2159 0.36703)
						(xy -0.21209 0.37719) (xy -0.20701 0.38735) (xy -0.2032 0.39624) (xy -0.19812 0.4064) (xy -0.17272 0.44196)
						(xy -0.1651 0.44958) (xy -0.1651 0.7366) (xy -0.16256 0.76835) (xy -0.1524 0.8001) (xy -0.13716 0.82804)
						(xy -0.11684 0.85344) (xy -0.09144 0.87376) (xy -0.0635 0.889) (xy -0.03175 0.89916) (xy 0 0.9017)
						(xy 0.03175 0.89916) (xy 0.0635 0.889) (xy 0.09144 0.87376) (xy 0.11684 0.85344) (xy 0.13716 0.82804)
						(xy 0.1524 0.8001) (xy 0.16256 0.76835) (xy 0.1651 0.7366) (xy 0.1651 0.44958) (xy 0.17272 0.44196)
						(xy 0.19812 0.4064) (xy 0.2032 0.39624) (xy 0.20701 0.38735) (xy 0.21209 0.37719) (xy 0.2159 0.36703)
						(xy 0.21844 0.35687) (xy 0.22225 0.34544) (xy 0.22352 0.33528) (xy 0.22606 0.32512) (xy 0.22733 0.31369)
						(xy 0.22733 0.30353) (xy 0.2286 0.2921) (xy 0.22733 0.28067) (xy 0.22733 0.27051) (xy 0.22606 0.25908)
						(xy 0.22352 0.24892) (xy 0.22225 0.23876) (xy 0.21844 0.22733) (xy 0.2159 0.21717) (xy 0.21209 0.20701)
						(xy 0.20701 0.19685) (xy 0.2032 0.18796) (xy 0.19812 0.1778) (xy 0.17272 0.14224) (xy 0.1651 0.13462)
						(xy 0.1651 -0.7366) (xy 0.16256 -0.76835) (xy 0.1524 -0.8001) (xy 0.13716 -0.82804) (xy 0.11684 -0.85344)
						(xy 0.09144 -0.87376) (xy 0.0635 -0.889) (xy 0.03175 -0.89916)
					)
					(width 0)
					(fill yes)
				)
			)
		)
		(pad "27" smd custom
			(at -23.850092 -4.100068 180)
			(size 0.1143 0.1143)
			(layers "B.Cu" "B.Mask" "B.Paste")
			(net "M_B_DQS_DP1")
			(options
				(clearance outline)
				(anchor circle)
			)
			(primitives
				(gr_poly
					(pts
						(xy 0 -0.9017) (xy -0.03175 -0.89916) (xy -0.0635 -0.889) (xy -0.09144 -0.87376) (xy -0.11684 -0.85344)
						(xy -0.13716 -0.82804) (xy -0.1524 -0.8001) (xy -0.16256 -0.76835) (xy -0.1651 -0.7366) (xy -0.1651 -0.19685)
						(xy -0.17272 -0.18923) (xy -0.17907 -0.18034) (xy -0.18669 -0.17145) (xy -0.19177 -0.16256) (xy -0.19812 -0.15367)
						(xy -0.20828 -0.13335) (xy -0.21971 -0.10287) (xy -0.22225 -0.09271) (xy -0.22479 -0.08128) (xy -0.22606 -0.07112)
						(xy -0.2286 -0.05969) (xy -0.2286 -0.01651) (xy -0.22606 -0.00508) (xy -0.22479 0.00508) (xy -0.22225 0.01651)
						(xy -0.21971 0.02667) (xy -0.20828 0.05715) (xy -0.19812 0.07747) (xy -0.19177 0.08636) (xy -0.18669 0.09525)
						(xy -0.17907 0.10414) (xy -0.17272 0.11303) (xy -0.1651 0.12065) (xy -0.1651 0.7366) (xy -0.16256 0.76835)
						(xy -0.1524 0.8001) (xy -0.13716 0.82804) (xy -0.11684 0.85344) (xy -0.09144 0.87376) (xy -0.0635 0.889)
						(xy -0.03175 0.89916) (xy 0 0.9017) (xy 0.03175 0.89916) (xy 0.0635 0.889) (xy 0.09144 0.87376)
						(xy 0.11684 0.85344) (xy 0.13716 0.82804) (xy 0.1524 0.8001) (xy 0.16256 0.76835) (xy 0.1651 0.7366)
						(xy 0.1651 0.11938) (xy 0.17272 0.11176) (xy 0.19812 0.0762) (xy 0.2032 0.06604) (xy 0.20701 0.05715)
						(xy 0.21209 0.04699) (xy 0.2159 0.03683) (xy 0.21844 0.02667) (xy 0.22225 0.01524) (xy 0.22352 0.00508)
						(xy 0.22606 -0.00508) (xy 0.22733 -0.01651) (xy 0.22733 -0.02667) (xy 0.2286 -0.0381) (xy 0.22733 -0.04953)
						(xy 0.22733 -0.05969) (xy 0.22606 -0.07112) (xy 0.22352 -0.08128) (xy 0.22225 -0.09144) (xy 0.21844 -0.10287)
						(xy 0.2159 -0.11303) (xy 0.21209 -0.12319) (xy 0.20701 -0.13335) (xy 0.2032 -0.14224) (xy 0.19812 -0.1524)
						(xy 0.17272 -0.18796) (xy 0.1651 -0.19558) (xy 0.1651 -0.7366) (xy 0.16256 -0.76835) (xy 0.1524 -0.8001)
						(xy 0.13716 -0.82804) (xy 0.11684 -0.85344) (xy 0.09144 -0.87376) (xy 0.0635 -0.889) (xy 0.03175 -0.89916)
					)
					(width 0)
					(fill yes)
				)
			)
		)
	)
)
